(kicad_pcb
	(version 20260206)
	(generator "pcbnew")
	(generator_version "10.0")
	(general
		(thickness 1.6)
		(legacy_teardrops no)
	)
	(paper "A4")
	(title_block
		(title "04192023_DAF0TMB3IC0_F0TG_MB_C_brd_V02_OCP.brd")
		(comment 1 "Grand Teton / footprints 6325-6331 of 8354")
	)
	(layers
		(0 "F.Cu" signal "TOP")
		(4 "In1.Cu" signal "GND")
		(6 "In2.Cu" signal "IN1")
		(8 "In3.Cu" signal "GND1")
		(10 "In4.Cu" signal "IN2")
		(12 "In5.Cu" signal "GND2")
		(14 "In6.Cu" signal "IN3")
		(16 "In7.Cu" signal "GND3")
		(18 "In8.Cu" signal "VCC")
		(20 "In9.Cu" signal "VCC1")
		(22 "In10.Cu" signal "GND4")
		(24 "In11.Cu" signal "IN4")
		(26 "In12.Cu" signal "GND5")
		(28 "In13.Cu" signal "IN5")
		(30 "In14.Cu" signal "GND6")
		(32 "In15.Cu" signal "IN6")
		(34 "In16.Cu" signal "GND7")
		(2 "B.Cu" signal "BOTTOM")
		(9 "F.Adhes" user "F.Adhesive")
		(11 "B.Adhes" user "B.Adhesive")
		(13 "F.Paste" user "Package Geometry/Pastemask Top")
		(15 "B.Paste" user "Package Geometry/Pastemask Bottom")
		(5 "F.SilkS" user "Ref Des/Silkscreen Top")
		(7 "B.SilkS" user "Ref Des/Silkscreen Bottom")
		(1 "F.Mask" user "Board Geometry/Soldermask Top")
		(3 "B.Mask" user "Board Geometry/Soldermask Bottom")
		(17 "Dwgs.User" user "User.Drawings")
		(19 "Cmts.User" user "User.Comments")
		(21 "Eco1.User" user "User.Eco1")
		(23 "Eco2.User" user "User.Eco2")
		(25 "Edge.Cuts" user "Board Geometry/Outline")
		(27 "Margin" user)
		(31 "F.CrtYd" user "Package Geometry/Place Bound Top")
		(29 "B.CrtYd" user "Package Geometry/Place Bound Bottom")
		(35 "F.Fab" user "Ref Des/Assembly Top")
		(33 "B.Fab" user "Ref Des/Assembly Bottom")
	)
	(footprint ""
		(layer "B.Cu")
		(at 243.586 -223.139 90)
		(property "Reference" "U96"
			(at -1.194562 3.014472 270)
			(unlocked yes)
			(layer "B.SilkS")
			(effects
				(font
					(size 0.7874 0.5842)
					(thickness 0.1524)
				)
				(justify left mirror)
			)
		)
		(property "Value" ""
			(at 0 0 90)
			(layer "B.Fab")
			(effects
				(font
					(size 1.27 1.27)
				)
				(justify mirror)
			)
		)
		(duplicate_pad_numbers_are_jumpers no)
		(fp_line
			(start 1.463548 -1.549908)
			(end 0.787908 -1.549908)
			(stroke
				(width 0.1524)
				(type default)
			)
			(layer "B.SilkS")
		)
		(fp_line
			(start 0.787908 -1.549908)
			(end 0 -0.762)
			(stroke
				(width 0.1524)
				(type default)
			)
			(layer "B.SilkS")
		)
		(fp_line
			(start -0.762 -1.549908)
			(end -1.463548 -1.549908)
			(stroke
				(width 0.1524)
				(type default)
			)
			(layer "B.SilkS")
		)
		(fp_line
			(start -1.463548 -1.549908)
			(end -1.463548 1.549908)
			(stroke
				(width 0.1524)
				(type default)
			)
			(layer "B.SilkS")
		)
		(fp_line
			(start 0 -0.762)
			(end -0.762 -1.549908)
			(stroke
				(width 0.1524)
				(type default)
			)
			(layer "B.SilkS")
		)
		(fp_line
			(start 1.463548 1.549908)
			(end 1.463548 -1.549908)
			(stroke
				(width 0.1524)
				(type default)
			)
			(layer "B.SilkS")
		)
		(fp_line
			(start -1.463548 1.549908)
			(end 1.463548 1.549908)
			(stroke
				(width 0.1524)
				(type default)
			)
			(layer "B.SilkS")
		)
		(fp_poly
			(pts
				(xy 3.4417 -0.959866) (xy 3.4417 -1.579626) (xy 2.82194 -1.269746)
			)
			(stroke
				(width 0)
				(type default)
			)
			(fill yes)
			(layer "B.SilkS")
		)
		(fp_line
			(start 1.549908 -1.549908)
			(end -1.549908 -1.549908)
			(stroke
				(width 0.1)
				(type default)
			)
			(layer "B.Fab")
		)
		(fp_line
			(start -1.549908 -1.549908)
			(end -1.549908 1.549908)
			(stroke
				(width 0.1)
				(type default)
			)
			(layer "B.Fab")
		)
		(fp_line
			(start 1.549908 1.549908)
			(end 1.549908 -1.549908)
			(stroke
				(width 0.1)
				(type default)
			)
			(layer "B.Fab")
		)
		(fp_line
			(start -1.549908 1.549908)
			(end 1.549908 1.549908)
			(stroke
				(width 0.1)
				(type default)
			)
			(layer "B.Fab")
		)
		(fp_poly
			(pts
				(xy 3.4798 -1.359916) (xy 2.86004 -1.050036) (xy 3.4798 -0.740156)
			)
			(stroke
				(width 0)
				(type default)
			)
			(fill yes)
			(layer "B.Fab")
		)
		(pad "1" smd rect
			(at 2.175002 -1.050036 180)
			(size 0.6096 1.1684)
			(layers "B.Cu" "B.Mask" "B.Paste")
			(net "PVDD18_S5_P0")
		)
		(pad "2" smd rect
			(at 2.175002 -0.32512 180)
			(size 0.4318 1.1684)
			(layers "B.Cu" "B.Mask" "B.Paste")
			(net "SMB_CPU0_CPU1_SEC_SCL_R1")
		)
		(pad "3" smd rect
			(at 2.175002 0.32512 180)
			(size 0.4318 1.1684)
			(layers "B.Cu" "B.Mask" "B.Paste")
			(net "SMB_CPU0_CPU1_SEC_SDA_R1")
		)
		(pad "4" smd rect
			(at 2.175002 1.050036 180)
			(size 0.6096 1.1684)
			(layers "B.Cu" "B.Mask" "B.Paste")
			(net "GND")
		)
		(pad "5" smd rect
			(at -2.175002 1.050036 180)
			(size 0.6096 1.1684)
			(layers "B.Cu" "B.Mask" "B.Paste")
			(net "PU_U96_EN")
		)
		(pad "6" smd rect
			(at -2.175002 0.32512 180)
			(size 0.4318 1.1684)
			(layers "B.Cu" "B.Mask" "B.Paste")
			(net "SMB_CPU0_CPU1_SEC_SDA")
		)
		(pad "7" smd rect
			(at -2.175002 -0.32512 180)
			(size 0.4318 1.1684)
			(layers "B.Cu" "B.Mask" "B.Paste")
			(net "SMB_CPU0_CPU1_SEC_SCL")
		)
		(pad "8" smd rect
			(at -2.175002 -1.050036 180)
			(size 0.6096 1.1684)
			(layers "B.Cu" "B.Mask" "B.Paste")
			(net "P3V3_AUX")
		)
	)
	(footprint ""
		(layer "B.Cu")
		(at 371.551454 -250.89231)
		(property "Reference" "C2166"
			(at 0 0 0)
			(layer "B.SilkS")
			(hide yes)
			(effects
				(font
					(size 1.27 1.27)
				)
				(justify mirror)
			)
		)
		(property "Value" ""
			(at 0 0 0)
			(layer "B.Fab")
			(effects
				(font
					(size 1.27 1.27)
				)
				(justify mirror)
			)
		)
		(duplicate_pad_numbers_are_jumpers no)
		(fp_line
			(start -0.7874 -0.4064)
			(end -0.7874 0.4064)
			(stroke
				(width 0.1524)
				(type default)
			)
			(layer "B.SilkS")
		)
		(fp_line
			(start -0.7874 0.4064)
			(end 0.7874 0.4064)
			(stroke
				(width 0.1524)
				(type default)
			)
			(layer "B.SilkS")
		)
		(fp_line
			(start 0.7874 -0.4064)
			(end -0.7874 -0.4064)
			(stroke
				(width 0.1524)
				(type default)
			)
			(layer "B.SilkS")
		)
		(fp_line
			(start 0.7874 0.4064)
			(end 0.7874 -0.4064)
			(stroke
				(width 0.1524)
				(type default)
			)
			(layer "B.SilkS")
		)
		(fp_line
			(start -0.67945 -0.3048)
			(end -0.67945 0.3048)
			(stroke
				(width 0.1)
				(type default)
			)
			(layer "B.Fab")
		)
		(fp_line
			(start -0.67945 0.3048)
			(end -0.120396 0.3048)
			(stroke
				(width 0.1)
				(type default)
			)
			(layer "B.Fab")
		)
		(fp_line
			(start -0.12065 -0.3048)
			(end -0.67945 -0.3048)
			(stroke
				(width 0.1)
				(type default)
			)
			(layer "B.Fab")
		)
		(fp_line
			(start -0.12065 -0.2794)
			(end -0.12065 -0.3048)
			(stroke
				(width 0.1)
				(type default)
			)
			(layer "B.Fab")
		)
		(fp_line
			(start -0.120396 0.2794)
			(end 0.12065 0.2794)
			(stroke
				(width 0.1)
				(type default)
			)
			(layer "B.Fab")
		)
		(fp_line
			(start -0.120396 0.3048)
			(end -0.120396 0.2794)
			(stroke
				(width 0.1)
				(type default)
			)
			(layer "B.Fab")
		)
		(fp_line
			(start 0.12065 -0.305054)
			(end 0.12065 -0.2794)
			(stroke
				(width 0.1)
				(type default)
			)
			(layer "B.Fab")
		)
		(fp_line
			(start 0.12065 -0.2794)
			(end -0.12065 -0.2794)
			(stroke
				(width 0.1)
				(type default)
			)
			(layer "B.Fab")
		)
		(fp_line
			(start 0.12065 0.2794)
			(end 0.12065 0.3048)
			(stroke
				(width 0.1)
				(type default)
			)
			(layer "B.Fab")
		)
		(fp_line
			(start 0.12065 0.3048)
			(end 0.67945 0.3048)
			(stroke
				(width 0.1)
				(type default)
			)
			(layer "B.Fab")
		)
		(fp_line
			(start 0.67945 -0.305054)
			(end 0.12065 -0.305054)
			(stroke
				(width 0.1)
				(type default)
			)
			(layer "B.Fab")
		)
		(fp_line
			(start 0.67945 0.3048)
			(end 0.67945 -0.305054)
			(stroke
				(width 0.1)
				(type default)
			)
			(layer "B.Fab")
		)
		(pad "1" smd circle
			(at 0.40005 0 180)
			(size 0 0)
			(layers "B.Cu" "B.Mask" "B.Paste")
			(net "PVDDCR_CPU0_P0")
		)
		(pad "2" smd circle
			(at -0.40005 0 180)
			(size 0 0)
			(layers "B.Cu" "B.Mask" "B.Paste")
			(net "GND")
		)
	)
	(footprint ""
		(layer "B.Cu")
		(at 426.53585 -34.737548 180)
		(property "Reference" "R734"
			(at 0 0 0)
			(layer "B.SilkS")
			(hide yes)
			(effects
				(font
					(size 1.27 1.27)
				)
				(justify mirror)
			)
		)
		(property "Value" ""
			(at 0 0 0)
			(layer "B.Fab")
			(effects
				(font
					(size 1.27 1.27)
				)
				(justify mirror)
			)
		)
		(duplicate_pad_numbers_are_jumpers no)
		(fp_line
			(start 0.7874 0.4064)
			(end 0.7874 -0.4064)
			(stroke
				(width 0.1524)
				(type default)
			)
			(layer "B.SilkS")
		)
		(fp_line
			(start 0.7874 -0.4064)
			(end -0.7874 -0.4064)
			(stroke
				(width 0.1524)
				(type default)
			)
			(layer "B.SilkS")
		)
		(fp_line
			(start -0.7874 0.4064)
			(end 0.7874 0.4064)
			(stroke
				(width 0.1524)
				(type default)
			)
			(layer "B.SilkS")
		)
		(fp_line
			(start -0.7874 -0.4064)
			(end -0.7874 0.4064)
			(stroke
				(width 0.1524)
				(type default)
			)
			(layer "B.SilkS")
		)
		(fp_line
			(start 0.67945 0.3048)
			(end 0.67945 -0.305054)
			(stroke
				(width 0.1)
				(type default)
			)
			(layer "B.Fab")
		)
		(fp_line
			(start 0.67945 -0.305054)
			(end 0.12065 -0.305054)
			(stroke
				(width 0.1)
				(type default)
			)
			(layer "B.Fab")
		)
		(fp_line
			(start 0.12065 0.3048)
			(end 0.67945 0.3048)
			(stroke
				(width 0.1)
				(type default)
			)
			(layer "B.Fab")
		)
		(fp_line
			(start 0.12065 0.2794)
			(end 0.12065 0.3048)
			(stroke
				(width 0.1)
				(type default)
			)
			(layer "B.Fab")
		)
		(fp_line
			(start 0.12065 -0.2794)
			(end -0.12065 -0.2794)
			(stroke
				(width 0.1)
				(type default)
			)
			(layer "B.Fab")
		)
		(fp_line
			(start 0.12065 -0.305054)
			(end 0.12065 -0.2794)
			(stroke
				(width 0.1)
				(type default)
			)
			(layer "B.Fab")
		)
		(fp_line
			(start -0.120396 0.3048)
			(end -0.120396 0.2794)
			(stroke
				(width 0.1)
				(type default)
			)
			(layer "B.Fab")
		)
		(fp_line
			(start -0.120396 0.2794)
			(end 0.12065 0.2794)
			(stroke
				(width 0.1)
				(type default)
			)
			(layer "B.Fab")
		)
		(fp_line
			(start -0.12065 -0.2794)
			(end -0.12065 -0.3048)
			(stroke
				(width 0.1)
				(type default)
			)
			(layer "B.Fab")
		)
		(fp_line
			(start -0.12065 -0.3048)
			(end -0.67945 -0.3048)
			(stroke
				(width 0.1)
				(type default)
			)
			(layer "B.Fab")
		)
		(fp_line
			(start -0.67945 0.3048)
			(end -0.120396 0.3048)
			(stroke
				(width 0.1)
				(type default)
			)
			(layer "B.Fab")
		)
		(fp_line
			(start -0.67945 -0.3048)
			(end -0.67945 0.3048)
			(stroke
				(width 0.1)
				(type default)
			)
			(layer "B.Fab")
		)
		(pad "1" smd circle
			(at 0.40005 0)
			(size 0 0)
			(layers "B.Cu" "B.Mask" "B.Paste")
			(net "PRSNT_CPU0_N")
		)
		(pad "2" smd circle
			(at -0.40005 0)
			(size 0 0)
			(layers "B.Cu" "B.Mask" "B.Paste")
			(net "FM_PRSNT_CPU0_N")
		)
	)
	(footprint ""
		(layer "B.Cu")
		(at 381.418338 -396.393162 -90)
		(property "Reference" "C1002"
			(at 0 0 90)
			(layer "B.SilkS")
			(hide yes)
			(effects
				(font
					(size 1.27 1.27)
				)
				(justify mirror)
			)
		)
		(property "Value" ""
			(at 0 0 90)
			(layer "B.Fab")
			(effects
				(font
					(size 1.27 1.27)
				)
				(justify mirror)
			)
		)
		(duplicate_pad_numbers_are_jumpers no)
		(fp_line
			(start -0.299974 0.150114)
			(end 0.299974 0.150114)
			(stroke
				(width 0.1)
				(type default)
			)
			(layer "B.Fab")
		)
		(fp_line
			(start 0.299974 0.150114)
			(end 0.299974 -0.150114)
			(stroke
				(width 0.1)
				(type default)
			)
			(layer "B.Fab")
		)
		(fp_line
			(start -0.299974 -0.150114)
			(end -0.299974 0.150114)
			(stroke
				(width 0.1)
				(type default)
			)
			(layer "B.Fab")
		)
		(fp_line
			(start 0.299974 -0.150114)
			(end -0.299974 -0.150114)
			(stroke
				(width 0.1)
				(type default)
			)
			(layer "B.Fab")
		)
		(pad "1" smd rect
			(at 0.2667 0 90)
			(size 0.3048 0.381)
			(layers "B.Cu" "B.Mask" "B.Paste")
			(net "P1V8_CPU0_RT3_1A_1D")
		)
		(pad "2" smd rect
			(at -0.2667 0 90)
			(size 0.3048 0.381)
			(layers "B.Cu" "B.Mask" "B.Paste")
			(net "GND")
		)
	)
	(footprint ""
		(layer "B.Cu")
		(at 423.256456 -195.85051 180)
		(property "Reference" "R1681"
			(at 0 0 0)
			(layer "B.SilkS")
			(hide yes)
			(effects
				(font
					(size 1.27 1.27)
				)
				(justify mirror)
			)
		)
		(property "Value" ""
			(at 0 0 0)
			(layer "B.Fab")
			(effects
				(font
					(size 1.27 1.27)
				)
				(justify mirror)
			)
		)
		(duplicate_pad_numbers_are_jumpers no)
		(fp_line
			(start 0.7874 0.4064)
			(end 0.7874 -0.4064)
			(stroke
				(width 0.1524)
				(type default)
			)
			(layer "B.SilkS")
		)
		(fp_line
			(start 0.7874 -0.4064)
			(end -0.7874 -0.4064)
			(stroke
				(width 0.1524)
				(type default)
			)
			(layer "B.SilkS")
		)
		(fp_line
			(start -0.7874 0.4064)
			(end 0.7874 0.4064)
			(stroke
				(width 0.1524)
				(type default)
			)
			(layer "B.SilkS")
		)
		(fp_line
			(start -0.7874 -0.4064)
			(end -0.7874 0.4064)
			(stroke
				(width 0.1524)
				(type default)
			)
			(layer "B.SilkS")
		)
		(fp_line
			(start 0.67945 0.3048)
			(end 0.67945 -0.305054)
			(stroke
				(width 0.1)
				(type default)
			)
			(layer "B.Fab")
		)
		(fp_line
			(start 0.67945 -0.305054)
			(end 0.12065 -0.305054)
			(stroke
				(width 0.1)
				(type default)
			)
			(layer "B.Fab")
		)
		(fp_line
			(start 0.12065 0.3048)
			(end 0.67945 0.3048)
			(stroke
				(width 0.1)
				(type default)
			)
			(layer "B.Fab")
		)
		(fp_line
			(start 0.12065 0.2794)
			(end 0.12065 0.3048)
			(stroke
				(width 0.1)
				(type default)
			)
			(layer "B.Fab")
		)
		(fp_line
			(start 0.12065 -0.2794)
			(end -0.12065 -0.2794)
			(stroke
				(width 0.1)
				(type default)
			)
			(layer "B.Fab")
		)
		(fp_line
			(start 0.12065 -0.305054)
			(end 0.12065 -0.2794)
			(stroke
				(width 0.1)
				(type default)
			)
			(layer "B.Fab")
		)
		(fp_line
			(start -0.120396 0.3048)
			(end -0.120396 0.2794)
			(stroke
				(width 0.1)
				(type default)
			)
			(layer "B.Fab")
		)
		(fp_line
			(start -0.120396 0.2794)
			(end 0.12065 0.2794)
			(stroke
				(width 0.1)
				(type default)
			)
			(layer "B.Fab")
		)
		(fp_line
			(start -0.12065 -0.2794)
			(end -0.12065 -0.3048)
			(stroke
				(width 0.1)
				(type default)
			)
			(layer "B.Fab")
		)
		(fp_line
			(start -0.12065 -0.3048)
			(end -0.67945 -0.3048)
			(stroke
				(width 0.1)
				(type default)
			)
			(layer "B.Fab")
		)
		(fp_line
			(start -0.67945 0.3048)
			(end -0.120396 0.3048)
			(stroke
				(width 0.1)
				(type default)
			)
			(layer "B.Fab")
		)
		(fp_line
			(start -0.67945 -0.3048)
			(end -0.67945 0.3048)
			(stroke
				(width 0.1)
				(type default)
			)
			(layer "B.Fab")
		)
		(pad "1" smd circle
			(at 0.40005 0)
			(size 0 0)
			(layers "B.Cu" "B.Mask" "B.Paste")
			(net "I3C_SPD_DDRGL_CPU0_SDA")
		)
		(pad "2" smd circle
			(at -0.40005 0)
			(size 0 0)
			(layers "B.Cu" "B.Mask" "B.Paste")
			(net "I3C_SPD_DDRH_CPU0_SDA")
		)
	)
	(footprint ""
		(layer "B.Cu")
		(at 348.151958 -261.870952)
		(property "Reference" "C2650"
			(at 0 0 0)
			(layer "B.SilkS")
			(hide yes)
			(effects
				(font
					(size 1.27 1.27)
				)
				(justify mirror)
			)
		)
		(property "Value" ""
			(at 0 0 0)
			(layer "B.Fab")
			(effects
				(font
					(size 1.27 1.27)
				)
				(justify mirror)
			)
		)
		(duplicate_pad_numbers_are_jumpers no)
		(fp_line
			(start -0.7874 -0.4064)
			(end -0.7874 0.4064)
			(stroke
				(width 0.1524)
				(type default)
			)
			(layer "B.SilkS")
		)
		(fp_line
			(start -0.7874 0.4064)
			(end 0.7874 0.4064)
			(stroke
				(width 0.1524)
				(type default)
			)
			(layer "B.SilkS")
		)
		(fp_line
			(start 0.7874 -0.4064)
			(end -0.7874 -0.4064)
			(stroke
				(width 0.1524)
				(type default)
			)
			(layer "B.SilkS")
		)
		(fp_line
			(start 0.7874 0.4064)
			(end 0.7874 -0.4064)
			(stroke
				(width 0.1524)
				(type default)
			)
			(layer "B.SilkS")
		)
		(fp_line
			(start -0.67945 -0.3048)
			(end -0.67945 0.3048)
			(stroke
				(width 0.1)
				(type default)
			)
			(layer "B.Fab")
		)
		(fp_line
			(start -0.67945 0.3048)
			(end -0.120396 0.3048)
			(stroke
				(width 0.1)
				(type default)
			)
			(layer "B.Fab")
		)
		(fp_line
			(start -0.12065 -0.3048)
			(end -0.67945 -0.3048)
			(stroke
				(width 0.1)
				(type default)
			)
			(layer "B.Fab")
		)
		(fp_line
			(start -0.12065 -0.2794)
			(end -0.12065 -0.3048)
			(stroke
				(width 0.1)
				(type default)
			)
			(layer "B.Fab")
		)
		(fp_line
			(start -0.120396 0.2794)
			(end 0.12065 0.2794)
			(stroke
				(width 0.1)
				(type default)
			)
			(layer "B.Fab")
		)
		(fp_line
			(start -0.120396 0.3048)
			(end -0.120396 0.2794)
			(stroke
				(width 0.1)
				(type default)
			)
			(layer "B.Fab")
		)
		(fp_line
			(start 0.12065 -0.305054)
			(end 0.12065 -0.2794)
			(stroke
				(width 0.1)
				(type default)
			)
			(layer "B.Fab")
		)
		(fp_line
			(start 0.12065 -0.2794)
			(end -0.12065 -0.2794)
			(stroke
				(width 0.1)
				(type default)
			)
			(layer "B.Fab")
		)
		(fp_line
			(start 0.12065 0.2794)
			(end 0.12065 0.3048)
			(stroke
				(width 0.1)
				(type default)
			)
			(layer "B.Fab")
		)
		(fp_line
			(start 0.12065 0.3048)
			(end 0.67945 0.3048)
			(stroke
				(width 0.1)
				(type default)
			)
			(layer "B.Fab")
		)
		(fp_line
			(start 0.67945 -0.305054)
			(end 0.12065 -0.305054)
			(stroke
				(width 0.1)
				(type default)
			)
			(layer "B.Fab")
		)
		(fp_line
			(start 0.67945 0.3048)
			(end 0.67945 -0.305054)
			(stroke
				(width 0.1)
				(type default)
			)
			(layer "B.Fab")
		)
		(pad "1" smd circle
			(at 0.40005 0 180)
			(size 0 0)
			(layers "B.Cu" "B.Mask" "B.Paste")
			(net "PVDDIO_P0")
		)
		(pad "2" smd circle
			(at -0.40005 0 180)
			(size 0 0)
			(layers "B.Cu" "B.Mask" "B.Paste")
			(net "GND")
		)
	)
	(footprint ""
		(layer "B.Cu")
		(at 90.036904 -408.517344 90)
		(property "Reference" "C6687"
			(at 0 0 90)
			(layer "B.SilkS")
			(hide yes)
			(effects
				(font
					(size 1.27 1.27)
				)
				(justify mirror)
			)
		)
		(property "Value" ""
			(at 0 0 90)
			(layer "B.Fab")
			(effects
				(font
					(size 1.27 1.27)
				)
				(justify mirror)
			)
		)
		(duplicate_pad_numbers_are_jumpers no)
		(fp_line
			(start 0.299974 -0.150114)
			(end -0.299974 -0.150114)
			(stroke
				(width 0.1)
				(type default)
			)
			(layer "B.Fab")
		)
		(fp_line
			(start -0.299974 -0.150114)
			(end -0.299974 0.150114)
			(stroke
				(width 0.1)
				(type default)
			)
			(layer "B.Fab")
		)
		(fp_line
			(start 0.299974 0.150114)
			(end 0.299974 -0.150114)
			(stroke
				(width 0.1)
				(type default)
			)
			(layer "B.Fab")
		)
		(fp_line
			(start -0.299974 0.150114)
			(end 0.299974 0.150114)
			(stroke
				(width 0.1)
				(type default)
			)
			(layer "B.Fab")
		)
		(pad "1" smd rect
			(at 0.2667 0 270)
			(size 0.3048 0.381)
			(layers "B.Cu" "B.Mask" "B.Paste")
			(net "P5E_CPU1_P1_TX_BUF_C_DP<13>")
		)
		(pad "2" smd rect
			(at -0.2667 0 270)
			(size 0.3048 0.381)
			(layers "B.Cu" "B.Mask" "B.Paste")
			(net "P5E_CPU1_P1_TX_BUF_DP<13>")
		)
	)
)
